# BASEBOARD_FAB2 (Tioga Pass) — schematic netlist excerpt (pin names and nets, part order shuffled) for the footprints in the layout excerpt that follows; sources: Cadence DE-HDL packaged netlist, KiCad conversion of Wiwynn_Tioga_Pass_MB.brd

R1D24  RES  0.0 5% CHIP  pkg 0402  page 199 : A = SMB_BMC_PMBUS_STBY_LVC3_SCL ; B = SMB_3V3SB_HSC_SCL_R
C3D17  CAP_A  22.0UF 4V 20% X6S  pkg 0603V  page 76 : A = PVCCMCP_CPU1 ; B = GND
C1A19  CAP  1.0UF 16V 10% X6S  pkg 0402  page 227 : A = VR_FET_SW_P12V_STBY_PVDDQ_KLM ; B = GND

(kicad_pcb
	(version 20260206)
	(generator "pcbnew")
	(generator_version "10.0")
	(general
		(thickness 1.6)
		(legacy_teardrops no)
	)
	(paper "A4")
	(title_block
		(title "Wiwynn_Tioga_Pass_MB.brd")
		(comment 1 "Tioga Pass / footprints 1063-1065 of 4770")
	)
	(layers
		(0 "F.Cu" signal "TOP")
		(4 "In1.Cu" signal "L2GND")
		(6 "In2.Cu" signal "L3")
		(8 "In3.Cu" signal "L4GND")
		(10 "In4.Cu" signal "L5")
		(12 "In5.Cu" signal "L6GND")
		(14 "In6.Cu" signal "L7VCC")
		(16 "In7.Cu" signal "L8VCC")
		(18 "In8.Cu" signal "L9GND")
		(20 "In9.Cu" signal "L10")
		(22 "In10.Cu" signal "L11GND")
		(24 "In11.Cu" signal "L12")
		(26 "In12.Cu" signal "L13GND")
		(2 "B.Cu" signal "BOTTOM")
		(9 "F.Adhes" user "F.Adhesive")
		(11 "B.Adhes" user "B.Adhesive")
		(13 "F.Paste" user "Package Geometry/Pastemask Top")
		(15 "B.Paste" user "Package Geometry/Pastemask Bottom")
		(5 "F.SilkS" user "Ref Des/Silkscreen Top")
		(7 "B.SilkS" user "Ref Des/Silkscreen Bottom")
		(1 "F.Mask" user "Board Geometry/Soldermask Top")
		(3 "B.Mask" user "Board Geometry/Soldermask Bottom")
		(17 "Dwgs.User" user "User.Drawings")
		(19 "Cmts.User" user "User.Comments")
		(21 "Eco1.User" user "User.Eco1")
		(23 "Eco2.User" user "User.Eco2")
		(25 "Edge.Cuts" user "Board Geometry/Outline")
		(27 "Margin" user)
		(31 "F.CrtYd" user "Package Geometry/Place Bound Top")
		(29 "B.CrtYd" user "Package Geometry/Place Bound Bottom")
		(35 "F.Fab" user "Ref Des/Assembly Top")
		(33 "B.Fab" user "Ref Des/Assembly Bottom")
	)
	(footprint ""
		(layer "F.Cu")
		(at -1.864868 -140.939012 -90)
		(property "Reference" "C1A19"
			(at 0 0 270)
			(layer "F.SilkS")
			(hide yes)
			(effects
				(font
					(size 1.27 1.27)
				)
			)
		)
		(property "Value" ""
			(at 0 0 270)
			(layer "F.Fab")
			(effects
				(font
					(size 1.27 1.27)
				)
			)
		)
		(duplicate_pad_numbers_are_jumpers no)
		(fp_poly
			(pts
				(xy 0.3048 -0.1016) (xy 0.3048 0.9906) (xy -0.3048 0.9906) (xy -0.3048 -0.1016)
			)
			(stroke
				(width 0)
				(type default)
			)
			(fill no)
			(layer "F.CrtYd")
		)
		(fp_line
			(start -0.3048 0.9906)
			(end 0.3048 0.9906)
			(stroke
				(width 0.1)
				(type default)
			)
			(layer "F.Fab")
		)
		(fp_line
			(start 0.3048 0.9906)
			(end 0.3048 -0.1016)
			(stroke
				(width 0.1)
				(type default)
			)
			(layer "F.Fab")
		)
		(fp_line
			(start -0.3048 -0.1016)
			(end -0.3048 0.9906)
			(stroke
				(width 0.1)
				(type default)
			)
			(layer "F.Fab")
		)
		(fp_line
			(start 0.3048 -0.1016)
			(end -0.3048 -0.1016)
			(stroke
				(width 0.1)
				(type default)
			)
			(layer "F.Fab")
		)
		(pad "1" smd rect
			(at 0 0 270)
			(size 0.508 0.508)
			(layers "F.Cu" "F.Mask" "F.Paste")
			(net "VR_FET_SW_P12V_STBY_PVDDQ_KLM")
		)
		(pad "2" smd rect
			(at 0 0.889 270)
			(size 0.508 0.508)
			(layers "F.Cu" "F.Mask" "F.Paste")
			(net "GND")
		)
		(zone
			(layer "F.Cu")
			(hatch none 0.5)
			(connect_pads
				(clearance 0)
			)
			(min_thickness 0.25)
			(keepout
				(tracks not_allowed)
				(vias allowed)
				(pads allowed)
				(copperpour not_allowed)
				(footprints allowed)
			)
			(placement
				(enabled no)
				(sheetname "")
			)
			(fill
				(thermal_gap 0.5)
				(thermal_bridge_width 0.5)
				(island_removal_mode 0)
			)
			(polygon
				(pts
					(xy -2.499868 -141.193012) (xy -2.499868 -140.685012) (xy -2.118868 -140.685012) (xy -2.118868 -141.193012)
				)
			)
		)
		(zone
			(layer "F.Cu")
			(hatch none 0.5)
			(connect_pads
				(clearance 0)
			)
			(min_thickness 0.25)
			(keepout
				(tracks allowed)
				(vias not_allowed)
				(pads allowed)
				(copperpour not_allowed)
				(footprints allowed)
			)
			(placement
				(enabled no)
				(sheetname "")
			)
			(fill
				(thermal_gap 0.5)
				(thermal_bridge_width 0.5)
				(island_removal_mode 0)
			)
			(polygon
				(pts
					(xy -2.118868 -141.193012) (xy -2.118868 -140.685012) (xy -2.499868 -140.685012) (xy -2.499868 -141.193012)
				)
			)
		)
	)
	(footprint ""
		(layer "F.Cu")
		(at 15.494 -80.4545)
		(property "Reference" "R1D24"
			(at 0 0 0)
			(layer "F.SilkS")
			(hide yes)
			(effects
				(font
					(size 1.27 1.27)
				)
			)
		)
		(property "Value" ""
			(at 0 0 0)
			(layer "F.Fab")
			(effects
				(font
					(size 1.27 1.27)
				)
			)
		)
		(duplicate_pad_numbers_are_jumpers no)
		(fp_rect
			(start 0.2794 0.9906)
			(end -0.2794 -0.1016)
			(stroke
				(width 0)
				(type default)
			)
			(fill no)
			(layer "F.CrtYd")
		)
		(fp_line
			(start -0.2794 -0.1016)
			(end -0.2794 0.9906)
			(stroke
				(width 0.1)
				(type default)
			)
			(layer "F.Fab")
		)
		(fp_line
			(start -0.2794 0.9906)
			(end 0.2794 0.9906)
			(stroke
				(width 0.1)
				(type default)
			)
			(layer "F.Fab")
		)
		(fp_line
			(start 0.2794 -0.1016)
			(end -0.2794 -0.1016)
			(stroke
				(width 0.1)
				(type default)
			)
			(layer "F.Fab")
		)
		(fp_line
			(start 0.2794 0.9906)
			(end 0.2794 -0.1016)
			(stroke
				(width 0.1)
				(type default)
			)
			(layer "F.Fab")
		)
		(pad "1" smd rect
			(at 0 0)
			(size 0.508 0.508)
			(layers "F.Cu" "F.Mask" "F.Paste")
			(net "SMB_BMC_PMBUS_STBY_LVC3_SCL")
		)
		(pad "2" smd rect
			(at 0 0.889)
			(size 0.508 0.508)
			(layers "F.Cu" "F.Mask" "F.Paste")
			(net "SMB_3V3SB_HSC_SCL_R")
		)
		(zone
			(layer "F.Cu")
			(hatch none 0.5)
			(connect_pads
				(clearance 0)
			)
			(min_thickness 0.25)
			(keepout
				(tracks allowed)
				(vias not_allowed)
				(pads allowed)
				(copperpour not_allowed)
				(footprints allowed)
			)
			(placement
				(enabled no)
				(sheetname "")
			)
			(fill
				(thermal_gap 0.5)
				(thermal_bridge_width 0.5)
				(island_removal_mode 0)
			)
			(polygon
				(pts
					(xy 15.748 -79.8195) (xy 15.748 -80.2005) (xy 15.24 -80.2005) (xy 15.24 -79.8195)
				)
			)
		)
		(zone
			(layer "F.Cu")
			(hatch none 0.5)
			(connect_pads
				(clearance 0)
			)
			(min_thickness 0.25)
			(keepout
				(tracks not_allowed)
				(vias allowed)
				(pads allowed)
				(copperpour not_allowed)
				(footprints allowed)
			)
			(placement
				(enabled no)
				(sheetname "")
			)
			(fill
				(thermal_gap 0.5)
				(thermal_bridge_width 0.5)
				(island_removal_mode 0)
			)
			(polygon
				(pts
					(xy 15.748 -79.8195) (xy 15.748 -80.2005) (xy 15.24 -80.2005) (xy 15.24 -79.8195)
				)
			)
		)
	)
	(footprint ""
		(layer "F.Cu")
		(at 108.16844 -73.318116)
		(property "Reference" "C3D17"
			(at 0 0 0)
			(layer "F.SilkS")
			(hide yes)
			(effects
				(font
					(size 1.27 1.27)
				)
			)
		)
		(property "Value" ""
			(at 0 0 0)
			(layer "F.Fab")
			(effects
				(font
					(size 1.27 1.27)
				)
			)
		)
		(duplicate_pad_numbers_are_jumpers no)
		(fp_poly
			(pts
				(xy -0.4953 -0.2032) (xy 0.4953 -0.2032) (xy 0.4953 1.6002) (xy -0.4953 1.6002)
			)
			(stroke
				(width 0)
				(type default)
			)
			(fill no)
			(layer "F.CrtYd")
		)
		(fp_line
			(start -0.4953 -0.2032)
			(end 0.4953 -0.2032)
			(stroke
				(width 0.1)
				(type default)
			)
			(layer "F.Fab")
		)
		(fp_line
			(start -0.4953 1.6002)
			(end -0.4953 -0.2032)
			(stroke
				(width 0.1)
				(type default)
			)
			(layer "F.Fab")
		)
		(fp_line
			(start 0.4953 -0.2032)
			(end 0.4953 1.6002)
			(stroke
				(width 0.1)
				(type default)
			)
			(layer "F.Fab")
		)
		(fp_line
			(start 0.4953 1.6002)
			(end -0.4953 1.6002)
			(stroke
				(width 0.1)
				(type default)
			)
			(layer "F.Fab")
		)
		(pad "1" smd rect
			(at 0 0)
			(size 0.762 0.889)
			(layers "F.Cu" "F.Mask" "F.Paste")
			(net "PVCCMCP_CPU1")
		)
		(pad "2" smd rect
			(at 0 1.397)
			(size 0.762 0.889)
			(layers "F.Cu" "F.Mask" "F.Paste")
			(net "GND")
		)
		(zone
			(layer "F.Cu")
			(hatch none 0.5)
			(connect_pads
				(clearance 0)
			)
			(min_thickness 0.25)
			(keepout
				(tracks not_allowed)
				(vias allowed)
				(pads allowed)
				(copperpour not_allowed)
				(footprints allowed)
			)
			(placement
				(enabled no)
				(sheetname "")
			)
			(fill
				(thermal_gap 0.5)
				(thermal_bridge_width 0.5)
				(island_removal_mode 0)
			)
			(polygon
				(pts
					(xy 107.78744 -72.873616) (xy 108.54944 -72.873616) (xy 108.54944 -72.365616) (xy 107.78744 -72.365616)
				)
			)
		)
	)
)
